(kicad_pcb
	(version 20260206)
	(generator "pcbnew")
	(generator_version "10.0")
	(general
		(thickness 1.6)
		(legacy_teardrops no)
	)
	(paper "A4")
	(title_block
		(title "baseboard — 13948-1b.1110WZS1818.brd")
		(comment 1 "Honey Badger (Wiwynn) / footprints 1358-1364 of 2523")
	)
	(layers
		(0 "F.Cu" signal "TOP")
		(4 "In1.Cu" signal "L2GND")
		(6 "In2.Cu" signal "L3")
		(8 "In3.Cu" signal "L4VCC")
		(10 "In4.Cu" signal "L5VCC")
		(12 "In5.Cu" signal "L6")
		(14 "In6.Cu" signal "L7GND")
		(2 "B.Cu" signal "BOTTOM")
		(9 "F.Adhes" user "F.Adhesive")
		(11 "B.Adhes" user "B.Adhesive")
		(13 "F.Paste" user "Package Geometry/Pastemask Top")
		(15 "B.Paste" user "Package Geometry/Pastemask Bottom")
		(5 "F.SilkS" user "Ref Des/Silkscreen Top")
		(7 "B.SilkS" user "Ref Des/Silkscreen Bottom")
		(1 "F.Mask" user "Board Geometry/Soldermask Top")
		(3 "B.Mask" user "Board Geometry/Soldermask Bottom")
		(17 "Dwgs.User" user "User.Drawings")
		(19 "Cmts.User" user "User.Comments")
		(21 "Eco1.User" user "User.Eco1")
		(23 "Eco2.User" user "User.Eco2")
		(25 "Edge.Cuts" user "Board Geometry/Outline")
		(27 "Margin" user)
		(31 "F.CrtYd" user "Package Geometry/Place Bound Top")
		(29 "B.CrtYd" user "Package Geometry/Place Bound Bottom")
		(35 "F.Fab" user "Ref Des/Assembly Top")
		(33 "B.Fab" user "Ref Des/Assembly Bottom")
	)
	(footprint ""
		(layer "F.Cu")
		(at 48.7172 -114.7572 180)
		(property "Reference" "SR941"
			(at 0 0 180)
			(layer "F.SilkS")
			(hide yes)
			(effects
				(font
					(size 1.27 1.27)
				)
			)
		)
		(property "Value" "0R2J-2-GP"
			(at 0.064008 -3.993896 180)
			(unlocked yes)
			(layer "F.Fab")
			(hide yes)
			(effects
				(font
					(size 1.016 1.016)
					(thickness 0.1524)
				)
			)
		)
		(property "Device Type" "R402H16"
			(at 0.064008 -5.517896 180)
			(unlocked yes)
			(layer "F.Fab")
			(hide yes)
			(effects
				(font
					(size 1.016 1.016)
					(thickness 0.1524)
				)
			)
		)
		(duplicate_pad_numbers_are_jumpers no)
		(fp_line
			(start 0.508 -0.9398)
			(end -0.508 -0.9398)
			(stroke
				(width 0.1524)
				(type default)
			)
			(layer "F.SilkS")
		)
		(fp_line
			(start -0.508 -0.9398)
			(end -0.508 0.9398)
			(stroke
				(width 0.1524)
				(type default)
			)
			(layer "F.SilkS")
		)
		(fp_rect
			(start -0.508 0.9398)
			(end 0.508 -0.9398)
			(stroke
				(width 0)
				(type default)
			)
			(fill no)
			(layer "F.CrtYd")
		)
		(fp_rect
			(start -0.508 0.9398)
			(end 0.508 -0.9398)
			(stroke
				(width 0)
				(type default)
			)
			(fill no)
			(layer "F.Fab")
		)
		(pad "1" smd custom
			(at 0 -0.4445 180)
			(size 0.1397 0.1397)
			(layers "F.Cu" "F.Mask" "F.Paste")
			(net "BMC_R_RXD5")
			(options
				(clearance outline)
				(anchor circle)
			)
			(primitives
				(gr_poly
					(pts
						(arc
							(start -0.1778 -0.2794)
							(mid -0.249642 -0.249642)
							(end -0.2794 -0.1778)
						)
						(arc
							(start -0.2794 0.1778)
							(mid -0.249642 0.249642)
							(end -0.1778 0.2794)
						)
						(arc
							(start 0.1778 0.2794)
							(mid 0.249642 0.249642)
							(end 0.2794 0.1778)
						)
						(arc
							(start 0.2794 -0.1778)
							(mid 0.249642 -0.249642)
							(end 0.1778 -0.2794)
						)
					)
					(width 0)
					(fill yes)
				)
			)
		)
		(pad "2" smd custom
			(at 0 0.4445 180)
			(size 0.1397 0.1397)
			(layers "F.Cu" "F.Mask" "F.Paste")
			(net "BMC_RXD5")
			(options
				(clearance outline)
				(anchor circle)
			)
			(primitives
				(gr_poly
					(pts
						(arc
							(start -0.1778 -0.2794)
							(mid -0.249642 -0.249642)
							(end -0.2794 -0.1778)
						)
						(arc
							(start -0.2794 0.1778)
							(mid -0.249642 0.249642)
							(end -0.1778 0.2794)
						)
						(arc
							(start 0.1778 0.2794)
							(mid 0.249642 0.249642)
							(end 0.2794 0.1778)
						)
						(arc
							(start 0.2794 -0.1778)
							(mid 0.249642 -0.249642)
							(end 0.1778 -0.2794)
						)
					)
					(width 0)
					(fill yes)
				)
			)
		)
	)
	(footprint ""
		(layer "F.Cu")
		(at 184.031128 -14.151864)
		(property "Reference" "R195"
			(at 0 0 0)
			(layer "F.SilkS")
			(hide yes)
			(effects
				(font
					(size 1.27 1.27)
				)
			)
		)
		(property "Value" "4K7R2F-GP"
			(at 0.064008 -3.993896 0)
			(unlocked yes)
			(layer "F.Fab")
			(hide yes)
			(effects
				(font
					(size 1.016 1.016)
					(thickness 0.1524)
				)
			)
		)
		(property "Device Type" "R402H16"
			(at 0.064008 -5.517896 0)
			(unlocked yes)
			(layer "F.Fab")
			(hide yes)
			(effects
				(font
					(size 1.016 1.016)
					(thickness 0.1524)
				)
			)
		)
		(duplicate_pad_numbers_are_jumpers no)
		(fp_line
			(start -0.508 -0.9398)
			(end -0.508 0.9398)
			(stroke
				(width 0.1524)
				(type default)
			)
			(layer "F.SilkS")
		)
		(fp_line
			(start 0.508 -0.9398)
			(end -0.508 -0.9398)
			(stroke
				(width 0.1524)
				(type default)
			)
			(layer "F.SilkS")
		)
		(fp_rect
			(start -0.508 0.9398)
			(end 0.508 -0.9398)
			(stroke
				(width 0)
				(type default)
			)
			(fill no)
			(layer "F.CrtYd")
		)
		(fp_rect
			(start -0.508 0.9398)
			(end 0.508 -0.9398)
			(stroke
				(width 0)
				(type default)
			)
			(fill no)
			(layer "F.Fab")
		)
		(pad "1" smd custom
			(at 0 -0.4445)
			(size 0.1397 0.1397)
			(layers "F.Cu" "F.Mask" "F.Paste")
			(net "TEMP_1_A0")
			(options
				(clearance outline)
				(anchor circle)
			)
			(primitives
				(gr_poly
					(pts
						(arc
							(start -0.1778 -0.2794)
							(mid -0.249642 -0.249642)
							(end -0.2794 -0.1778)
						)
						(arc
							(start -0.2794 0.1778)
							(mid -0.249642 0.249642)
							(end -0.1778 0.2794)
						)
						(arc
							(start 0.1778 0.2794)
							(mid 0.249642 0.249642)
							(end 0.2794 0.1778)
						)
						(arc
							(start 0.2794 -0.1778)
							(mid 0.249642 -0.249642)
							(end 0.1778 -0.2794)
						)
					)
					(width 0)
					(fill yes)
				)
			)
		)
		(pad "2" smd custom
			(at 0 0.4445)
			(size 0.1397 0.1397)
			(layers "F.Cu" "F.Mask" "F.Paste")
			(net "GND")
			(options
				(clearance outline)
				(anchor circle)
			)
			(primitives
				(gr_poly
					(pts
						(arc
							(start -0.1778 -0.2794)
							(mid -0.249642 -0.249642)
							(end -0.2794 -0.1778)
						)
						(arc
							(start -0.2794 0.1778)
							(mid -0.249642 0.249642)
							(end -0.1778 0.2794)
						)
						(arc
							(start 0.1778 0.2794)
							(mid 0.249642 0.249642)
							(end 0.2794 0.1778)
						)
						(arc
							(start 0.2794 -0.1778)
							(mid 0.249642 -0.249642)
							(end 0.1778 -0.2794)
						)
					)
					(width 0)
					(fill yes)
				)
			)
		)
	)
	(footprint ""
		(layer "F.Cu")
		(at 260.477 -34.29)
		(property "Reference" "PR57"
			(at 0 0 0)
			(layer "F.SilkS")
			(hide yes)
			(effects
				(font
					(size 1.27 1.27)
				)
			)
		)
		(property "Value" "10KR2F-2-GP"
			(at 0.064008 -3.993896 0)
			(unlocked yes)
			(layer "F.Fab")
			(hide yes)
			(effects
				(font
					(size 1.016 1.016)
					(thickness 0.1524)
				)
			)
		)
		(property "Device Type" "R402H16"
			(at 0.064008 -5.517896 0)
			(unlocked yes)
			(layer "F.Fab")
			(hide yes)
			(effects
				(font
					(size 1.016 1.016)
					(thickness 0.1524)
				)
			)
		)
		(duplicate_pad_numbers_are_jumpers no)
		(fp_line
			(start -0.508 -0.9398)
			(end -0.508 0.9398)
			(stroke
				(width 0.1524)
				(type default)
			)
			(layer "F.SilkS")
		)
		(fp_line
			(start 0.508 -0.9398)
			(end -0.508 -0.9398)
			(stroke
				(width 0.1524)
				(type default)
			)
			(layer "F.SilkS")
		)
		(fp_rect
			(start -0.508 0.9398)
			(end 0.508 -0.9398)
			(stroke
				(width 0)
				(type default)
			)
			(fill no)
			(layer "F.CrtYd")
		)
		(fp_rect
			(start -0.508 0.9398)
			(end 0.508 -0.9398)
			(stroke
				(width 0)
				(type default)
			)
			(fill no)
			(layer "F.Fab")
		)
		(pad "1" smd custom
			(at 0 -0.4445)
			(size 0.1397 0.1397)
			(layers "F.Cu" "F.Mask" "F.Paste")
			(net "P1V8_STBY_VFB")
			(options
				(clearance outline)
				(anchor circle)
			)
			(primitives
				(gr_poly
					(pts
						(arc
							(start -0.1778 -0.2794)
							(mid -0.249642 -0.249642)
							(end -0.2794 -0.1778)
						)
						(arc
							(start -0.2794 0.1778)
							(mid -0.249642 0.249642)
							(end -0.1778 0.2794)
						)
						(arc
							(start 0.1778 0.2794)
							(mid 0.249642 0.249642)
							(end 0.2794 0.1778)
						)
						(arc
							(start 0.2794 -0.1778)
							(mid 0.249642 -0.249642)
							(end 0.1778 -0.2794)
						)
					)
					(width 0)
					(fill yes)
				)
			)
		)
		(pad "2" smd custom
			(at 0 0.4445)
			(size 0.1397 0.1397)
			(layers "F.Cu" "F.Mask" "F.Paste")
			(net "AGND_P1V8_STBY")
			(options
				(clearance outline)
				(anchor circle)
			)
			(primitives
				(gr_poly
					(pts
						(arc
							(start -0.1778 -0.2794)
							(mid -0.249642 -0.249642)
							(end -0.2794 -0.1778)
						)
						(arc
							(start -0.2794 0.1778)
							(mid -0.249642 0.249642)
							(end -0.1778 0.2794)
						)
						(arc
							(start 0.1778 0.2794)
							(mid 0.249642 0.249642)
							(end 0.2794 0.1778)
						)
						(arc
							(start 0.2794 -0.1778)
							(mid 0.249642 -0.249642)
							(end 0.1778 -0.2794)
						)
					)
					(width 0)
					(fill yes)
				)
			)
		)
	)
	(footprint ""
		(layer "F.Cu")
		(at 173.99 -88.519 90)
		(property "Reference" "PTC5"
			(at 0 0 90)
			(layer "F.SilkS")
			(hide yes)
			(effects
				(font
					(size 1.27 1.27)
				)
			)
		)
		(property "Value" "SE470UF2VDM-GP"
			(at 0 -9.6012 90)
			(unlocked yes)
			(layer "F.Fab")
			(hide yes)
			(effects
				(font
					(size 1.016 1.016)
					(thickness 0.1524)
				)
			)
		)
		(property "Device Type" "CT7343H83"
			(at 0 -11.1252 90)
			(unlocked yes)
			(layer "F.Fab")
			(hide yes)
			(effects
				(font
					(size 1.016 1.016)
					(thickness 0.1524)
				)
			)
		)
		(duplicate_pad_numbers_are_jumpers no)
		(fp_line
			(start 2.286 -4.8768)
			(end -2.286 -4.8768)
			(stroke
				(width 0.1524)
				(type default)
			)
			(layer "F.SilkS")
		)
		(fp_line
			(start -2.286 -4.8768)
			(end -2.286 -2.032)
			(stroke
				(width 0.1524)
				(type default)
			)
			(layer "F.SilkS")
		)
		(fp_line
			(start 2.1082 -4.699)
			(end -2.1082 -4.699)
			(stroke
				(width 0.508)
				(type default)
			)
			(layer "F.SilkS")
		)
		(fp_line
			(start 2.286 -2.032)
			(end 2.286 -4.8768)
			(stroke
				(width 0.1524)
				(type default)
			)
			(layer "F.SilkS")
		)
		(fp_line
			(start 2.286 2.032)
			(end 2.286 4.8768)
			(stroke
				(width 0.1524)
				(type default)
			)
			(layer "F.SilkS")
		)
		(fp_line
			(start 2.286 4.8768)
			(end -2.286 4.8768)
			(stroke
				(width 0.1524)
				(type default)
			)
			(layer "F.SilkS")
		)
		(fp_line
			(start -2.286 4.8768)
			(end -2.286 2.032)
			(stroke
				(width 0.1524)
				(type default)
			)
			(layer "F.SilkS")
		)
		(fp_rect
			(start -2.1463 3.6449)
			(end 2.1463 -3.6449)
			(stroke
				(width 0)
				(type default)
			)
			(fill no)
			(layer "F.CrtYd")
		)
		(fp_poly
			(pts
				(xy -2.54 4.953) (xy -2.54 4.2926) (xy -3.81 4.2926) (xy -3.81 -4.2926) (xy -2.54 -4.2926) (xy -2.54 -4.953)
				(xy 2.54 -4.953) (xy 2.54 -4.2926) (xy 3.81 -4.2926) (xy 3.81 -1.6256) (xy 2.1463 -1.6256) (xy 2.1463 -3.6449)
				(xy -2.1463 -3.6449) (xy -2.1463 3.6449) (xy 2.1463 3.6449) (xy 2.1463 -1.6129) (xy 3.81 -1.6129)
				(xy 3.81 4.2926) (xy 2.54 4.2926) (xy 2.54 4.953)
			)
			(stroke
				(width 0)
				(type default)
			)
			(fill no)
			(layer "F.CrtYd")
		)
		(fp_rect
			(start 2.54 4.2926)
			(end 3.81 -4.2926)
			(stroke
				(width 0)
				(type default)
			)
			(fill no)
			(layer "F.Fab")
		)
		(fp_rect
			(start -3.81 4.2926)
			(end -2.54 -4.2926)
			(stroke
				(width 0)
				(type default)
			)
			(fill no)
			(layer "F.Fab")
		)
		(fp_rect
			(start -2.54 4.953)
			(end 2.54 -4.953)
			(stroke
				(width 0)
				(type default)
			)
			(fill no)
			(layer "F.Fab")
		)
		(pad "1" smd rect
			(at 0 -3.1496 90)
			(size 2.413 2.286)
			(layers "F.Cu" "F.Mask" "F.Paste")
			(net "P0V9_E")
		)
		(pad "2" smd rect
			(at 0 3.1496 90)
			(size 2.413 2.286)
			(layers "F.Cu" "F.Mask" "F.Paste")
			(net "GND")
		)
		(zone
			(layer "F.Cu")
			(hatch none 0.5)
			(connect_pads
				(clearance 0)
			)
			(min_thickness 0.25)
			(keepout
				(tracks allowed)
				(vias not_allowed)
				(pads allowed)
				(copperpour not_allowed)
				(footprints allowed)
			)
			(placement
				(enabled no)
				(sheetname "")
			)
			(fill
				(thermal_gap 0.5)
				(thermal_bridge_width 0.5)
				(island_removal_mode 0)
			)
			(polygon
				(pts
					(xy 172.3009 -90.0303) (xy 169.3926 -90.0303) (xy 169.3926 -87.0077) (xy 172.2882 -87.0077) (xy 172.6184 -87.0077)
					(xy 172.6184 -90.0303)
				)
			)
		)
		(zone
			(layer "F.Cu")
			(hatch none 0.5)
			(connect_pads
				(clearance 0)
			)
			(min_thickness 0.25)
			(keepout
				(tracks allowed)
				(vias not_allowed)
				(pads allowed)
				(copperpour not_allowed)
				(footprints allowed)
			)
			(placement
				(enabled no)
				(sheetname "")
			)
			(fill
				(thermal_gap 0.5)
				(thermal_bridge_width 0.5)
				(island_removal_mode 0)
			)
			(polygon
				(pts
					(xy 178.5874 -87.0077) (xy 178.5874 -90.0303) (xy 175.6918 -90.0303) (xy 175.3616 -90.0303) (xy 175.3616 -87.0077)
					(xy 175.6918 -87.0077)
				)
			)
		)
	)
	(footprint ""
		(layer "F.Cu")
		(at 188.722 -145.669)
		(property "Reference" "SC1294"
			(at 0 0 0)
			(layer "F.SilkS")
			(hide yes)
			(effects
				(font
					(size 1.27 1.27)
				)
			)
		)
		(property "Value" "SCD1U16V2KX-3GP"
			(at 1.1811 -2.7051 0)
			(unlocked yes)
			(layer "F.Fab")
			(hide yes)
			(effects
				(font
					(size 1.016 1.016)
					(thickness 0.1524)
				)
			)
		)
		(property "Device Type" "C402H22"
			(at 1.1811 -4.2291 0)
			(unlocked yes)
			(layer "F.Fab")
			(hide yes)
			(effects
				(font
					(size 1.016 1.016)
					(thickness 0.1524)
				)
			)
		)
		(duplicate_pad_numbers_are_jumpers no)
		(fp_rect
			(start -0.4318 0.9525)
			(end 0.4318 -0.9525)
			(stroke
				(width 0)
				(type default)
			)
			(fill no)
			(layer "F.CrtYd")
		)
		(fp_rect
			(start -0.4318 0.9525)
			(end 0.4318 -0.9525)
			(stroke
				(width 0)
				(type default)
			)
			(fill no)
			(layer "F.Fab")
		)
		(pad "1" smd custom
			(at 0 -0.4445)
			(size 0.1524 0.1524)
			(layers "F.Cu" "F.Mask" "F.Paste")
			(net "P1V8_E")
			(options
				(clearance outline)
				(anchor circle)
			)
			(primitives
				(gr_poly
					(pts
						(arc
							(start 0.3048 -0.2032)
							(mid 0.275042 -0.275042)
							(end 0.2032 -0.3048)
						)
						(arc
							(start -0.2032 -0.3048)
							(mid -0.275042 -0.275042)
							(end -0.3048 -0.2032)
						)
						(arc
							(start -0.3048 0.2032)
							(mid -0.275042 0.275042)
							(end -0.2032 0.3048)
						)
						(arc
							(start 0.2032 0.3048)
							(mid 0.275042 0.275042)
							(end 0.3048 0.2032)
						)
					)
					(width 0)
					(fill yes)
				)
			)
		)
		(pad "2" smd custom
			(at 0 0.4445)
			(size 0.1524 0.1524)
			(layers "F.Cu" "F.Mask" "F.Paste")
			(net "GND")
			(options
				(clearance outline)
				(anchor circle)
			)
			(primitives
				(gr_poly
					(pts
						(arc
							(start 0.3048 -0.2032)
							(mid 0.275042 -0.275042)
							(end 0.2032 -0.3048)
						)
						(arc
							(start -0.2032 -0.3048)
							(mid -0.275042 -0.275042)
							(end -0.3048 -0.2032)
						)
						(arc
							(start -0.3048 0.2032)
							(mid -0.275042 0.275042)
							(end -0.2032 0.3048)
						)
						(arc
							(start 0.2032 0.3048)
							(mid 0.275042 0.275042)
							(end 0.3048 0.2032)
						)
					)
					(width 0)
					(fill yes)
				)
			)
		)
	)
	(footprint ""
		(layer "F.Cu")
		(at 282.058872 -215.591136)
		(property "Reference" "PC89"
			(at 0 0 0)
			(layer "F.SilkS")
			(hide yes)
			(effects
				(font
					(size 1.27 1.27)
				)
			)
		)
		(property "Value" "SCD1U16V2KX-3GP"
			(at 1.1811 -2.7051 0)
			(unlocked yes)
			(layer "F.Fab")
			(hide yes)
			(effects
				(font
					(size 1.016 1.016)
					(thickness 0.1524)
				)
			)
		)
		(property "Device Type" "C402H22"
			(at 1.1811 -4.2291 0)
			(unlocked yes)
			(layer "F.Fab")
			(hide yes)
			(effects
				(font
					(size 1.016 1.016)
					(thickness 0.1524)
				)
			)
		)
		(duplicate_pad_numbers_are_jumpers no)
		(fp_rect
			(start -0.4318 0.9525)
			(end 0.4318 -0.9525)
			(stroke
				(width 0)
				(type default)
			)
			(fill no)
			(layer "F.CrtYd")
		)
		(fp_rect
			(start -0.4318 0.9525)
			(end 0.4318 -0.9525)
			(stroke
				(width 0)
				(type default)
			)
			(fill no)
			(layer "F.Fab")
		)
		(pad "1" smd custom
			(at 0 -0.4445)
			(size 0.1524 0.1524)
			(layers "F.Cu" "F.Mask" "F.Paste")
			(net "TPS74801_1V53_STBY_EN")
			(options
				(clearance outline)
				(anchor circle)
			)
			(primitives
				(gr_poly
					(pts
						(arc
							(start 0.3048 -0.2032)
							(mid 0.275042 -0.275042)
							(end 0.2032 -0.3048)
						)
						(arc
							(start -0.2032 -0.3048)
							(mid -0.275042 -0.275042)
							(end -0.3048 -0.2032)
						)
						(arc
							(start -0.3048 0.2032)
							(mid -0.275042 0.275042)
							(end -0.2032 0.3048)
						)
						(arc
							(start 0.2032 0.3048)
							(mid 0.275042 0.275042)
							(end 0.3048 0.2032)
						)
					)
					(width 0)
					(fill yes)
				)
			)
		)
		(pad "2" smd custom
			(at 0 0.4445)
			(size 0.1524 0.1524)
			(layers "F.Cu" "F.Mask" "F.Paste")
			(net "GND")
			(options
				(clearance outline)
				(anchor circle)
			)
			(primitives
				(gr_poly
					(pts
						(arc
							(start 0.3048 -0.2032)
							(mid 0.275042 -0.275042)
							(end 0.2032 -0.3048)
						)
						(arc
							(start -0.2032 -0.3048)
							(mid -0.275042 -0.275042)
							(end -0.3048 -0.2032)
						)
						(arc
							(start -0.3048 0.2032)
							(mid -0.275042 0.275042)
							(end -0.2032 0.3048)
						)
						(arc
							(start 0.2032 0.3048)
							(mid 0.275042 0.275042)
							(end 0.3048 0.2032)
						)
					)
					(width 0)
					(fill yes)
				)
			)
		)
	)
	(footprint ""
		(layer "F.Cu")
		(at 116.713 -69.342 -90)
		(property "Reference" "R587"
			(at 0 0 270)
			(layer "F.SilkS")
			(hide yes)
			(effects
				(font
					(size 1.27 1.27)
				)
			)
		)
		(property "Value" "0R2J-2-GP"
			(at 0.064008 -3.993896 270)
			(unlocked yes)
			(layer "F.Fab")
			(hide yes)
			(effects
				(font
					(size 1.016 1.016)
					(thickness 0.1524)
				)
			)
		)
		(property "Device Type" "R402H16"
			(at 0.064008 -5.517896 270)
			(unlocked yes)
			(layer "F.Fab")
			(hide yes)
			(effects
				(font
					(size 1.016 1.016)
					(thickness 0.1524)
				)
			)
		)
		(duplicate_pad_numbers_are_jumpers no)
		(fp_line
			(start -0.508 -0.9398)
			(end -0.508 0.9398)
			(stroke
				(width 0.1524)
				(type default)
			)
			(layer "F.SilkS")
		)
		(fp_line
			(start 0.508 -0.9398)
			(end -0.508 -0.9398)
			(stroke
				(width 0.1524)
				(type default)
			)
			(layer "F.SilkS")
		)
		(fp_rect
			(start -0.508 0.9398)
			(end 0.508 -0.9398)
			(stroke
				(width 0)
				(type default)
			)
			(fill no)
			(layer "F.CrtYd")
		)
		(fp_rect
			(start -0.508 0.9398)
			(end 0.508 -0.9398)
			(stroke
				(width 0)
				(type default)
			)
			(fill no)
			(layer "F.Fab")
		)
		(pad "1" smd custom
			(at 0 -0.4445 270)
			(size 0.1397 0.1397)
			(layers "F.Cu" "F.Mask" "F.Paste")
			(net "BMC_I2C_D_SDA")
			(options
				(clearance outline)
				(anchor circle)
			)
			(primitives
				(gr_poly
					(pts
						(arc
							(start -0.1778 -0.2794)
							(mid -0.249642 -0.249642)
							(end -0.2794 -0.1778)
						)
						(arc
							(start -0.2794 0.1778)
							(mid -0.249642 0.249642)
							(end -0.1778 0.2794)
						)
						(arc
							(start 0.1778 0.2794)
							(mid 0.249642 0.249642)
							(end 0.2794 0.1778)
						)
						(arc
							(start 0.2794 -0.1778)
							(mid 0.249642 -0.249642)
							(end 0.1778 -0.2794)
						)
					)
					(width 0)
					(fill yes)
				)
			)
		)
		(pad "2" smd custom
			(at 0 0.4445 270)
			(size 0.1397 0.1397)
			(layers "F.Cu" "F.Mask" "F.Paste")
			(net "TEMP_4_SDA")
			(options
				(clearance outline)
				(anchor circle)
			)
			(primitives
				(gr_poly
					(pts
						(arc
							(start -0.1778 -0.2794)
							(mid -0.249642 -0.249642)
							(end -0.2794 -0.1778)
						)
						(arc
							(start -0.2794 0.1778)
							(mid -0.249642 0.249642)
							(end -0.1778 0.2794)
						)
						(arc
							(start 0.1778 0.2794)
							(mid 0.249642 0.249642)
							(end 0.2794 0.1778)
						)
						(arc
							(start 0.2794 -0.1778)
							(mid 0.249642 -0.249642)
							(end 0.1778 -0.2794)
						)
					)
					(width 0)
					(fill yes)
				)
			)
		)
	)
)
